# BASEBOARD_FAB2 (Tioga Pass) — schematic netlist excerpt (pin names and nets, part order shuffled) for the footprints in the layout excerpt that follows; sources: Cadence DE-HDL packaged netlist, KiCad conversion of Wiwynn_Tioga_Pass_MB.brd

R6D2  RES  49.9 1% CHIP  pkg 0402  page 21 : A = A_CPU0_MCP01_RBIAS ; B = GND
C5G3  CAP_A  47UF 4V 20% X5R  pkg 0603V  page 217 : A = PVDDQ_ABC ; B = GND
R12W36  RES  0.0 5% EMPTY  pkg 0402  page 226 : A = NC_PVDDQ_KLM_GP0 ; B = PWRGD_PVDDQ_KLM

(kicad_pcb
	(version 20260206)
	(generator "pcbnew")
	(generator_version "10.0")
	(general
		(thickness 1.6)
		(legacy_teardrops no)
	)
	(paper "A4")
	(title_block
		(title "Wiwynn_Tioga_Pass_MB.brd")
		(comment 1 "Tioga Pass / footprints 495-497 of 4770")
	)
	(layers
		(0 "F.Cu" signal "TOP")
		(4 "In1.Cu" signal "L2GND")
		(6 "In2.Cu" signal "L3")
		(8 "In3.Cu" signal "L4GND")
		(10 "In4.Cu" signal "L5")
		(12 "In5.Cu" signal "L6GND")
		(14 "In6.Cu" signal "L7VCC")
		(16 "In7.Cu" signal "L8VCC")
		(18 "In8.Cu" signal "L9GND")
		(20 "In9.Cu" signal "L10")
		(22 "In10.Cu" signal "L11GND")
		(24 "In11.Cu" signal "L12")
		(26 "In12.Cu" signal "L13GND")
		(2 "B.Cu" signal "BOTTOM")
		(9 "F.Adhes" user "F.Adhesive")
		(11 "B.Adhes" user "B.Adhesive")
		(13 "F.Paste" user "Package Geometry/Pastemask Top")
		(15 "B.Paste" user "Package Geometry/Pastemask Bottom")
		(5 "F.SilkS" user "Ref Des/Silkscreen Top")
		(7 "B.SilkS" user "Ref Des/Silkscreen Bottom")
		(1 "F.Mask" user "Board Geometry/Soldermask Top")
		(3 "B.Mask" user "Board Geometry/Soldermask Bottom")
		(17 "Dwgs.User" user "User.Drawings")
		(19 "Cmts.User" user "User.Comments")
		(21 "Eco1.User" user "User.Eco1")
		(23 "Eco2.User" user "User.Eco2")
		(25 "Edge.Cuts" user "Board Geometry/Outline")
		(27 "Margin" user)
		(31 "F.CrtYd" user "Package Geometry/Place Bound Top")
		(29 "B.CrtYd" user "Package Geometry/Place Bound Bottom")
		(35 "F.Fab" user "Ref Des/Assembly Top")
		(33 "B.Fab" user "Ref Des/Assembly Bottom")
	)
	(footprint ""
		(layer "F.Cu")
		(at -4.191 -125.222)
		(property "Reference" "R12W36"
			(at -0.8382 -0.67818 0)
			(unlocked yes)
			(layer "F.SilkS")
			(effects
				(font
					(size 0.4064 0.254)
					(thickness 0.1524)
				)
				(justify left)
			)
		)
		(property "Value" ""
			(at 0 0 0)
			(layer "F.Fab")
			(effects
				(font
					(size 1.27 1.27)
				)
			)
		)
		(duplicate_pad_numbers_are_jumpers no)
		(fp_poly
			(pts
				(xy -0.2794 -0.1016) (xy 0.2794 -0.1016) (xy 0.2794 0.9906) (xy -0.2794 0.9906)
			)
			(stroke
				(width 0)
				(type default)
			)
			(fill no)
			(layer "F.CrtYd")
		)
		(fp_line
			(start -0.2794 -0.1016)
			(end -0.2794 0.9906)
			(stroke
				(width 0.1)
				(type default)
			)
			(layer "F.Fab")
		)
		(fp_line
			(start -0.2794 0.9906)
			(end 0.2794 0.9906)
			(stroke
				(width 0.1)
				(type default)
			)
			(layer "F.Fab")
		)
		(fp_line
			(start 0.2794 -0.1016)
			(end -0.2794 -0.1016)
			(stroke
				(width 0.1)
				(type default)
			)
			(layer "F.Fab")
		)
		(fp_line
			(start 0.2794 0.9906)
			(end 0.2794 -0.1016)
			(stroke
				(width 0.1)
				(type default)
			)
			(layer "F.Fab")
		)
		(pad "1" smd rect
			(at 0 0)
			(size 0.508 0.508)
			(layers "F.Cu" "F.Mask" "F.Paste")
			(net "NC_PVDDQ_KLM_GP0")
		)
		(pad "2" smd rect
			(at 0 0.889)
			(size 0.508 0.508)
			(layers "F.Cu" "F.Mask" "F.Paste")
			(net "PWRGD_PVDDQ_KLM")
		)
		(zone
			(layer "F.Cu")
			(hatch none 0.5)
			(connect_pads
				(clearance 0)
			)
			(min_thickness 0.25)
			(keepout
				(tracks allowed)
				(vias not_allowed)
				(pads allowed)
				(copperpour not_allowed)
				(footprints allowed)
			)
			(placement
				(enabled no)
				(sheetname "")
			)
			(fill
				(thermal_gap 0.5)
				(thermal_bridge_width 0.5)
				(island_removal_mode 0)
			)
			(polygon
				(pts
					(xy -4.445 -124.968) (xy -3.937 -124.968) (xy -3.937 -124.587) (xy -4.445 -124.587)
				)
			)
		)
		(zone
			(layer "F.Cu")
			(hatch none 0.5)
			(connect_pads
				(clearance 0)
			)
			(min_thickness 0.25)
			(keepout
				(tracks not_allowed)
				(vias allowed)
				(pads allowed)
				(copperpour not_allowed)
				(footprints allowed)
			)
			(placement
				(enabled no)
				(sheetname "")
			)
			(fill
				(thermal_gap 0.5)
				(thermal_bridge_width 0.5)
				(island_removal_mode 0)
			)
			(polygon
				(pts
					(xy -4.445 -124.587) (xy -3.937 -124.587) (xy -3.937 -124.968) (xy -4.445 -124.968)
				)
			)
		)
	)
	(footprint ""
		(layer "F.Cu")
		(at 278.13 -83.8454)
		(property "Reference" "R6D2"
			(at 0 0 0)
			(layer "F.SilkS")
			(hide yes)
			(effects
				(font
					(size 1.27 1.27)
				)
			)
		)
		(property "Value" ""
			(at 0 0 0)
			(layer "F.Fab")
			(effects
				(font
					(size 1.27 1.27)
				)
			)
		)
		(duplicate_pad_numbers_are_jumpers no)
		(fp_poly
			(pts
				(xy -0.2794 -0.1016) (xy 0.2794 -0.1016) (xy 0.2794 0.9906) (xy -0.2794 0.9906)
			)
			(stroke
				(width 0)
				(type default)
			)
			(fill no)
			(layer "F.CrtYd")
		)
		(fp_line
			(start -0.2794 -0.1016)
			(end -0.2794 0.9906)
			(stroke
				(width 0.1)
				(type default)
			)
			(layer "F.Fab")
		)
		(fp_line
			(start -0.2794 0.9906)
			(end 0.2794 0.9906)
			(stroke
				(width 0.1)
				(type default)
			)
			(layer "F.Fab")
		)
		(fp_line
			(start 0.2794 -0.1016)
			(end -0.2794 -0.1016)
			(stroke
				(width 0.1)
				(type default)
			)
			(layer "F.Fab")
		)
		(fp_line
			(start 0.2794 0.9906)
			(end 0.2794 -0.1016)
			(stroke
				(width 0.1)
				(type default)
			)
			(layer "F.Fab")
		)
		(pad "1" smd rect
			(at 0 0)
			(size 0.508 0.508)
			(layers "F.Cu" "F.Mask" "F.Paste")
			(net "A_CPU0_MCP01_RBIAS")
		)
		(pad "2" smd rect
			(at 0 0.889)
			(size 0.508 0.508)
			(layers "F.Cu" "F.Mask" "F.Paste")
			(net "GND")
		)
		(zone
			(layer "F.Cu")
			(hatch none 0.5)
			(connect_pads
				(clearance 0)
			)
			(min_thickness 0.25)
			(keepout
				(tracks allowed)
				(vias not_allowed)
				(pads allowed)
				(copperpour not_allowed)
				(footprints allowed)
			)
			(placement
				(enabled no)
				(sheetname "")
			)
			(fill
				(thermal_gap 0.5)
				(thermal_bridge_width 0.5)
				(island_removal_mode 0)
			)
			(polygon
				(pts
					(xy 277.876 -83.5914) (xy 278.384 -83.5914) (xy 278.384 -83.2104) (xy 277.876 -83.2104)
				)
			)
		)
		(zone
			(layer "F.Cu")
			(hatch none 0.5)
			(connect_pads
				(clearance 0)
			)
			(min_thickness 0.25)
			(keepout
				(tracks not_allowed)
				(vias allowed)
				(pads allowed)
				(copperpour not_allowed)
				(footprints allowed)
			)
			(placement
				(enabled no)
				(sheetname "")
			)
			(fill
				(thermal_gap 0.5)
				(thermal_bridge_width 0.5)
				(island_removal_mode 0)
			)
			(polygon
				(pts
					(xy 277.876 -83.2104) (xy 278.384 -83.2104) (xy 278.384 -83.5914) (xy 277.876 -83.5914)
				)
			)
		)
	)
	(footprint ""
		(layer "F.Cu")
		(at 252.1585 -12.954 -90)
		(property "Reference" "C5G3"
			(at 1.848866 0.752348 270)
			(unlocked yes)
			(layer "F.SilkS")
			(effects
				(font
					(size 1.27 0.9652)
					(thickness 0.1524)
				)
			)
		)
		(property "Value" ""
			(at 0 0 270)
			(layer "F.Fab")
			(effects
				(font
					(size 1.27 1.27)
				)
			)
		)
		(duplicate_pad_numbers_are_jumpers no)
		(fp_rect
			(start -0.500126 1.598422)
			(end 0.500126 -0.201422)
			(stroke
				(width 0)
				(type default)
			)
			(fill no)
			(layer "F.CrtYd")
		)
		(fp_line
			(start -0.500126 1.598422)
			(end -0.500126 -0.201422)
			(stroke
				(width 0.1)
				(type default)
			)
			(layer "F.Fab")
		)
		(fp_line
			(start 0.500126 1.598422)
			(end -0.500126 1.598422)
			(stroke
				(width 0.1)
				(type default)
			)
			(layer "F.Fab")
		)
		(fp_line
			(start -0.500126 -0.201422)
			(end 0.500126 -0.201422)
			(stroke
				(width 0.1)
				(type default)
			)
			(layer "F.Fab")
		)
		(fp_line
			(start 0.500126 -0.201422)
			(end 0.500126 1.598422)
			(stroke
				(width 0.1)
				(type default)
			)
			(layer "F.Fab")
		)
		(pad "1" smd rect
			(at 0 0 180)
			(size 0.889 0.9906)
			(layers "F.Cu" "F.Mask" "F.Paste")
			(net "PVDDQ_ABC")
		)
		(pad "2" smd rect
			(at 0 1.397 180)
			(size 0.889 0.9906)
			(layers "F.Cu" "F.Mask" "F.Paste")
			(net "GND")
		)
		(zone
			(layer "F.Cu")
			(hatch none 0.5)
			(connect_pads
				(clearance 0)
			)
			(min_thickness 0.25)
			(keepout
				(tracks allowed)
				(vias not_allowed)
				(pads allowed)
				(copperpour not_allowed)
				(footprints allowed)
			)
			(placement
				(enabled no)
				(sheetname "")
			)
			(fill
				(thermal_gap 0.5)
				(thermal_bridge_width 0.5)
				(island_removal_mode 0)
			)
			(polygon
				(pts
					(xy 251.206 -13.4493) (xy 251.206 -12.4587) (xy 251.714 -12.4587) (xy 251.714 -13.4493)
				)
			)
		)
		(zone
			(layer "F.Cu")
			(hatch none 0.5)
			(connect_pads
				(clearance 0)
			)
			(min_thickness 0.25)
			(keepout
				(tracks not_allowed)
				(vias allowed)
				(pads allowed)
				(copperpour not_allowed)
				(footprints allowed)
			)
			(placement
				(enabled no)
				(sheetname "")
			)
			(fill
				(thermal_gap 0.5)
				(thermal_bridge_width 0.5)
				(island_removal_mode 0)
			)
			(polygon
				(pts
					(xy 251.206 -13.4493) (xy 251.206 -12.4587) (xy 251.714 -12.4587) (xy 251.714 -13.4493)
				)
			)
		)
	)
)
